TITLE: Bill of Materials
DATE: 12/01/2015
DESIGN: baseboard_fab2
TEMPLATE: D:\Cadence\SPB_16.6\share\cdssetup\template.bom
CALLOUT: 

Part Name	Ref Des	Qty	STATUS	MATERIAL	PART_NUMBER	SKU	SIDE_SKU
0R2J-L-GP_SMD-RG5-0R2J-L-GP,63.R0034.L0L	R1L45	1	?	?	63.R0034.L0L	?	?
0R3J-0-U-GP_RCL_GP-0R3J-0-U-GP,63.00000.00L	R25W93,R25W120	2	?	?	63.00000.00L	?	?
120R2F-GP_RCL_GP-120R2F-GP,64.12005.6DL	R1T28,R25W1,R25W2,R25W3,R25W4,R25W5,R25W6,R25W7,R25W8,R25W9,R25W10,R25W11,R25W12,R25W13,R25W14,R25W15,R25W16,R25W17,R25W18,R25W19,R25W20,R25W21,R25W22,R25W23,R25W24,R25W25,R25W26,R25W27,R25W28,R25W29,R25W30,R25W31,R25W32,R25W33,R25W34,R25W35,R25W36,R25W37,R25W38,R25W39,R25W40,R25W41,R25W42,R25W43,R25W44,R25W45,R25W46,R25W47,R25W48,R25W49,R25W50,R25W51,R25W52	53	?	?	64.12005.6DL	?	?
21K5R2F-GP_RCL_GP-21K5R2F-GP,64.21525.6DL	R9W31	1	?	?	64.21525.6DL	?	?
232KR2F-2-GP_SMD-RG1-232KR2F-2-GP,64.23235.L0L	R6W3	1	?	?	64.23235.L0L	?	?
3D01R5F-GP_SMD-RG5-3D01R5F-GP,64.3R015.16L	RT2,RT4,RT6,RT7,RT10,RT12,RT13,RT16,RT18,RT20,RT22,RT24,RT26,RT27,RT29,RT32,RT34,RT35,RT38,RT39,RT42,RT43,RT45,RT48	24	NOPOP	?	64.3R015.16L	?	?
47KR2F-GP_RCL_GP-47KR2F-GP,64.47025.6DL	R3W4	1	?	?	64.47025.6DL	?	?
4K42R2F-GP_SMD-RG-4K42R2F-GP,64.44215.6DL	R9F6	1	?	?	64.44215.6DL	?	?
5K1R2F-2-GP_SMD-RG-5K1R2F-2-GP,64.51015.6DL	R9F31	1	?	?	64.51015.6DL	?	?
74CBTLV1G125_SMLF-IC,C88177-001	U1M4,U1M5,U1M6,U4R1,U6M1,U7D1,U9A5	7	Conditional	IC	C88177-001	?	?
82K5R2F-GP_SMD-RG-82K5R2F-GP,64.82525.6DL	R3W5	1	?	?	64.82525.6DL	?	?
ADC128D818_SM-IC,H63642-001	EU9G1	1	?	IC	H63642-001	?	?
ADM1085_SMT-IC,H46130-001	U7D3	1	Design	IC	H46130-001	?	?
ADM1278_SM-IC,G99251-001	EU1D2	1	Design	IC	G99251-001	?	?
ADM4073_SM-EMPTY,G12194-001	U1B3,U4C1	2	Design	EMPTY	G12194-001	?	?
ADM809_SMLF-IC,D23047-001	U1L3,U8E2	2	Conditional	IC	D23047-001	?	?
AST2520A1-GP-GP_ASIC2-GB1-AST2520A1-GP-GP,071.2520A.M001	U25W4	1	?	?	071.2520A.M001	?	?
AT24C64_SOICLF-IC,C47049-001	U6W3,U8D4	2	Conditional	IC	C47049-001	?	?
BATTERY_PLCLF-202168-001	BT8G1	1	Approved	?	202168-001	?	?
CAPP_2626-270UF,16V,20%,OSCON,A31228-047	C1B10,C1C1,C1C2,C1E18,C4C12,C4D2,C4E16,C7A19,C7G2	9	Design	OSCON	A31228-047	?	?
CAPP_3018-470UF,2.5V,20%,ALUM,699013-049	C3L6,C3L14,C3N14,C3N26,C3N35,C3N38,C3R4,C3U1,C3U5,C3U8,C4C1,C4E7,C4E24,C4L5,C4R1,C6A5,C6N1,C6N4,C6N9,C6P8,C6P14,C6P18,C6P23,C6R3,C6R5,C6R9,C6R12,C6R16,C7G28,C9L2,C9L4,C9L9,C9L12,C9N11,C9N20,C9N24,C9P5,C9P8,C9P18,C9P23,C9R3,C9R9,C9T5,C9U2,C9U5,C9U9	46	Design	ALUM	699013-049	?	?
CAPP_3018-470UF,6.3V,20%,POSCAP,724613-091	C8E4,C8F8,C8F14	3	Unqual	POSCAP	724613-091	?	?
CAPP_3018-68UF,16V,20%,TANT,724613-112	C1M5,C1R23,C3B6,C3T3,C3T6,C3T13,C3T15,C4B14,C4F4,C4F5,C4M6,C4M7,C6N5,C7M6,C9M3,C9T3	16	Unqual	TANT	724613-112	?	?
CAPP_4040LF-470UF,16V,20%,ALUM,A93539-036	C1B14,C1F7,C4B13,C4F6	4	Approved	ALUM	A93539-036	?	?
CAPP_7343-220UF,4V,20%,POSCAP,724613-067	C4F11,C4M1,C4T3,C6L8	4	?	POSCAP	724613-067	?	?
CAPP_7343HLF-330UF,10V,20%,POSCAP,724613-043	C9B8	1	Conditional	POSCAP	724613-043	?	?
CAPP_7343LF-330UF,6.3V,20%,POSCAP,724613-042	C3B3,C4F7,C6B7,C6F4	4	Conditional	POSCAP	724613-042	?	?
CAPP_SM-470UF,2V,20%,ALUM,699013-031	C2L25,C2L46,C3L18,C3L19,C3L20,C3L21,C7A27,C8A15	8	Conditional	ALUM	699013-031	?	?
CAPTIVE_SCREW_TH-HDW,H57868-001	RM1G1	1	?	HDW	H57868-001	?	?
CAP_0402-0.027UF,16V,10%,X7R,A36096-129	C4B6,C4G8,C7B11,C7F10	4	Design	X7R	A36096-129	?	?
CAP_0402-0.047UF,25V,10%,X7R,A36096-090	C3P45	1	Conditional	X7R	A36096-090	?	?
CAP_0402-0.1UF,16V,10%,EMPTY,A36096-030	C25W7,C25W8,C25W9	3	Approved	EMPTY	A36096-030	?	?
CAP_0402-0.220UF,16V,10%,X7R,A36096-104	C1A8,C1A18,C1C12,C1C24,C1D10,C1D20,C1D36,C1E11,C1F26,C1G11,C4C8,C4C17,C4D9,C4D28,C4D50,C4E17,C4E18,C7A12,C7A22,C7A43,C7A44,C7C14,C7G31,C7G38	24	Conditional	X7R	A36096-104	?	?
CAP_0402-0.22UF,16V,10%,EMPTY,A36096-155	C3P10,C3P12,C3P14,C3P16,C3P19,C3P21,C3P22,C3P24,C3P26,C3P29,C3P31,C3P33,C3P34,C3P36,C3P38,C3P41	16	?	EMPTY	A36096-155	?	?
CAP_0402-0.22UF,16V,10%,X7R,A36096-155	C1A13,C1B21,C1C4,C1D6,C1D16,C1D33,C1E7,C1E25,C1F2,C1F3,C1F4,C1F5,C1F6,C1F8,C1F10,C1F11,C1F12,C1F13,C1F14,C1F15,C1F16,C1F17,C1F18,C1F20,C1G5,C1G29,C1M6,C1M7,C1M8,C1M9,C1M10,C1M11,C1M12,C1M13,C1M14,C1M15,C1M16,C1M17,C1M18,C1M19,C1R1,C1R2,C1R3,C1R4,C1R5,C1R6,C1R7,C1R8,C1R9,C1R10,C2M14,C2M15,C2R7,C2R8,C2R9,C2R10,C2R13,C2R14,C2T10,C2T11,C2T13,C2T14,C2T20,C2T23,C2U3,C2U4,C2U5,C2U6,C2U7,C2U8,C2U9,C2U10,C2U11,C2U12,C2U13,C2U14,C2U15,C2U16,C2U17,C2U18,C3M1,C3M2,C3M3,C3M4,C3M11,C3M12,C3M13,C3M14,C3M25,C3M26,C3M28,C3M32,C3M33,C3M34,C3M35,C3M36,C3M37,C3M40,C3M41,C3M44,C3M45,C3N8,C3N9,C3N13,C3P11,C3P13,C3P15,C3P17,C3P18,C3P20,C3P23,C3P25,C3P27,C3P28,C3P30,C3P32,C3P35,C3P37,C3P39,C3P40,C4C5,C4D5,C4D13,C4D47,C4E5,C4E23,C4E27,C6B4,C6B5,C6B6,C6B8,C6B9,C6B10,C6B11,C6B12,C6B13,C6B14,C6B15,C6B16,C6B17,C6B18,C6B19,C6B20,C7A8,C7A17,C7A25,C7A41,C7B25,C7B26,C7B27,C7B28,C7B29,C7C1,C7C2,C7C3,C7C18,C7G5,C7G6,C7G7,C7G8,C7G9,C7G10,C7G11,C7G12,C7G13,C7G14,C7G15,C7G16,C7G17,C7G18,C7G19,C7G20,C7G21,C7G22,C7G23,C7G24,C7G25,C7G26,C7G34,C7G41,C8F7,C8F12,C8G1,C8G2,C8G3,C8G4,C8G5,C8G6,C8G7,C8G8,C8G9,C8G10,C9N1,C9N2,C9N3,C9N4,C9N5,C9N6,C9N7,C9N8,C9N9,C9N10,C9N12,C9N14,C9N15,C9N16,C9N17,C9N18,C826,C827,C828,C829,C830,C831,C832,C833,C834,C835,C840,C841,C842,C843,C844,C845	224	?	X7R	A36096-155	?	?
CAP_0402-1.0UF,16V,10%,X6S,D97712-011	C1A6,C1A9,C1A19,C1B20,C1C5,C1C15,C1C26,C1D7,C1D12,C1D17,C1D19,C1D23,C1D25,C1D32,C1D35,C1E8,C1E13,C1E24,C1F27,C1G6,C1G13,C1G28,C1L1,C1L19,C1U19,C3M9,C3P50,C3T10,C4A8,C4A9,C4A10,C4A14,C4C6,C4C9,C4C18,C4D7,C4D10,C4D16,C4D30,C4D46,C4D48,C4E10,C4E15,C4E19,C4E22,C4E26,C4G4,C4G15,C4G16,C4G18,C4G21,C6L11,C7A6,C7A7,C7A9,C7A10,C7A11,C7A16,C7A21,C7A24,C7C12,C7C17,C7D4,C7E14,C7G30,C7G33,C7G37,C7G40,C8E14,C9E11,C25W1,C25W2,C25W3,C25W4,C25W5,C25W6	76	?	X6S	D97712-011	?	?
CAP_0402-1.0UF,16V,10%,X7S,G71842-007	C9G5	1	Design	X7S	G71842-007	?	?
CAP_0402-1.0UF,6.3V,10%,X6S,D97712-004	C25W12,C25W23,C25W24,C25W25,C25W26,C25W27,C25W28,C25W32,C25W33,C25W35,C25W37,C25W40,C25W41,C25W42,C25W43,C25W44,C25W48,C25W51,C25W52,C25W53,C25W54,C25W56,C25W57,C25W60,C25W63,C25W66,C25W67,C25W71,CN8F1	29	Conditional	X6S	D97712-004	?	?
CAP_0402LF-0.01UF,25V,10%,X7R,A36096-045	C25W10,C25W11,CN8F2	3	Approved	X7R	A36096-045	?	?
CAP_0402LF-0.022UF,16V,10%,X7R,A36096-073	C8E15	1	Approved	X7R	A36096-073	?	?
CAP_0402LF-0.039UF,25V,10%,X7R,A36096-063	C9E7	1	Approved	X7R	A36096-063	?	?
CAP_0402LF-0.1UF,16V,10%,X7R,A36096-030	C6W1,C6W2,C6W10,C8W2,C25W13,C25W22	6	Approved	X7R	A36096-030	?	?
CAP_0402LF-10.0PF,50V,5%,COG,A36094-025	C9G22	1	Approved	COG	A36094-025	?	?
CAP_0402LF-100.0PF,50V,5%,COG,A36095-026	C4B4,C4G6,C7B10,C7F9,C25W16	5	Approved	COG	A36095-026	?	?
CAP_0402LF-1000PF,50V,10%,EMPTY,A36096-046	C4A2,C4A6,C4B5,C4G7,C4G12,C4G23,C7B9,C7F8,C8A10,C8E13,C8E17,C9F6,C9F9,C9W6	14	Approved	EMPTY	A36096-046	?	?
CAP_0402LF-1000PF,50V,10%,X7R,A36096-046	C1B4,C1B8,C1C8,C1C23,C1G21,C1G26,C3P2,C3P6,C4A3,C4A12,C4B8,C4D20,C4D33,C4D40,C4D42,C4G9,C4G13,C4G14,C7A35,C7B3,C7B12,C7E10,C7F11,C7F14,C7G1,C8A3,C8A9,C8A11,C8F2,C9F8,C9F10,C9W10,CT2,CT4,CT8,CT10,CT15,CT19,CT22,CT26,CT28,CT32,CT34,CT37,CT42,CT43,CT48,CT49,CT54,CT55,CT58,CT61,CT64,CT69,CT71,CTI7	56	Approved	X7R	A36096-046	?	?
CAP_0402LF-12.0PF,50V,5%,COG,A36095-043	C9F20,C9F21	2	Approved	COG	A36095-043	?	?
CAP_0402LF-15.0PF,50V,5%,COG,A36095-047	C7C4,C7C5	2	Approved	COG	A36095-047	?	?
CAP_0402LF-18PF,50V,5%,C0G,A36095-042	C7C13,C7C15	2	Approved	C0G	A36095-042	?	?
CAP_0402LF-22.0PF,50V,5%,COG,A36095-030	C9E8,C9E9	2	Approved	COG	A36095-030	?	?
CAP_0402LF-2200PF,50V,10%,X7R,A36096-075	C4B7,C4B9,C4G10,C4G11,C7B13,C7B14,C7F12,C7F13,C8F1	9	Approved	X7R	A36096-075	?	?
CAP_0402LF-220PF,50V,10%,X7R,A36096-050	C1B11,C1B12,C1C10,C1C11,C1C16,C1D1,C1G16,C1G24,C2L2,C3N39,C4D17,C4D18,C4D29,C4D44,C4D45,C7A28,C7A29,C7G3,C7G4,C8A2	20	Approved	X7R	A36096-050	?	?
CAP_0402LF-27.0PF,50V,5%,COG,A36095-038	C8F18,C8F19	2	Approved	COG	A36095-038	?	?
CAP_0402LF-270PF,50V,10%,X7R,A36096-065	C8E16	1	Approved	X7R	A36096-065	?	?
CAP_0402LF-33.0PF,50V,5%,COG,A36095-031	C8C1,C8C2	2	Approved	COG	A36095-031	?	?
CAP_0402LF-3300PF,50V,10%,EMPTY,A36096-091	C4A16,C4F12,C7A34,C7F3,C8F3	5	Approved	EMPTY	A36096-091	?	?
CAP_0402LF-47.0PF,50V,5%,COG,A36095-025	C1U21,C9G14,C9G15,C9G17,C9G18,C9G20,C9G21	7	Approved	COG	A36095-025	?	?
CAP_0402LF-47.0PF,50V,5%,EMPTY,A36095-025	C1E19,C1M4	2	Approved	EMPTY	A36095-025	?	?
CAP_0402LF-4700PF,50V,10%,EMPTY,A36096-066	C9G9,C9G12,C9G13,C9G16	4	Approved	EMPTY	A36096-066	?	?
CAP_0402LF-470PF,50V,10%,EMPTY,A36096-049	C2R6,C8D3	2	Approved	EMPTY	A36096-049	?	?
CAP_0402LF-470PF,50V,10%,X7R,A36096-049	C9F22,C9G1,C9G2,C9G3	4	Approved	X7R	A36096-049	?	?
CAP_0603-10UF,6.3V,20%,X6S,E15431-002	C1R13,C1R16,C1R17,C1R22,C1R30,C1T4,C1T7,C1T15,C1W7,C1W15,C2N14,C2N17,C2N21,C2N22,C2N23,C2N24,C7D2,C8A6,C8C3,C8C4,C8C5,C8C6,C8W1,C9E10,C9F3	25	Conditional	X6S	E15431-002	?	?
CAP_0603-4.7UF,6.3V,10%,X6S,E15431-003	C2R11,C3M10,C3T11,C4A7,C4A11,C6L12,C6U6,C6U11,C6U12	9	Conditional	X6S	E15431-003	?	?
CAP_0603LF-0.033UF,50V,10%,X7R,603269-064	C9P14	1	Approved	X7R	603269-064	?	?
CAP_0603LF-0.1UF,25V,10%,X7R,602433-020	C4B15,C4G26,C7B30,C7F4,C8A4,C8E6,C8E12	7	Conditional	X7R	602433-020	?	?
CAP_0603LF-10UF,4V,20%,X6S,E15431-001	C2D4,C2D5,C2D6,C2D7,C2D8,C2D9,C2D10,C2D11,C2D41,C2D42,C2D43,C2D44,C2M5,C2M10,C2N6,C3A3,C3A4,C3A7,C3A8,C3B1,C3B2,C3D3,C3F3,C3F4,C3G3,C3G4,C3G7,C3G8,C3M17,C3M18,C3M23,C3M24,C4A15,C4L1,C4L2,C4L3,C4L4,C4M3,C4M4,C4T5,C4T6,C4U1,C4U2,C4U3,C4U4,C5D6,C5D7,C5D8,C5D9,C5D10,C5D11,C5D12,C5D13,C5D54,C5D55,C5D56,C5D57,C6A2,C6A3,C6A6,C6A7,C6B1,C6B2,C6D1,C6F5,C6F6,C6G1,C6G2,C6G4,C6G5,C6L3,C6L4,C6L5,C6U13,C6U14,C6U15,C6U16,C7L2,C7L3,C7L6,C7L7,C7M3,C7M4,C7T2,C7T3,C7U3,C7U4,C7U5,C7U6	89	Conditional	X6S	E15431-001	?	?
CAP_0805-100UF,4V,20%,X5R,602433-112	C2A8,C2A16,C2G7,C2G16,C4T4,C5A10,C5A20,C5G9,C5G20,C5L1,C5L2,C5L3,C5L14,C5M8,C5M12,C5U1,C5U10,C5U13,C5U14,C5U15,C7L1,C7T1,C7U7,C8L1,C8L2,C8L11,C8M7,C8M11,C8U1,C8U8,C8U11,C8U12	32	?	X5R	602433-112	?	?
CAP_0805-100UF,4V,20%,X5R,602433-112	C5G21,C5G22,C5G77,C5G78,C5G115,C5G116,C5G117,C5G118	8	?	X5R	602433-112	?	1S
CAP_0805-10UF,16V,10%,X6S,C95333-007	C1B18,C1E12,C1E15,C1E21,C1M26,C1M27,C2T22,C2U1,C2U2,C3L2,C3L4,C3L7,C3L8,C3L9,C3L10,C3L11,C3L12,C3L13,C3L15,C3L16,C3L17,C3M8,C3M15,C3M16,C3N33,C3N34,C3N36,C3T8,C3T12,C3T14,C3U2,C3U3,C3U4,C3U6,C3U7,C3U9,C4A19,C4G2,C6L10,C6M3,C6M5,C6N2,C6N3,C6N6,C6N8,C6N10,C6N11,C6P7,C6P13,C6P15,C6P17,C6P19,C6P20,C6P22,C6P24,C6R4,C6R6,C6R8,C6R10,C6R11,C6R13,C6R14,C6U4,C6U7,C6U8,C7B5,C7E6,C7E8,C7F5,C8B6,C8B12,C9B1,C9B2,C9L5,C9L6,C9L10,C9L11,C9L13,C9L14,C9M4,C9M10,C9N13,C9N19,C9N21,C9N25,C9N26,C9N27,C9P1,C9P2,C9P4,C9P7,C9P9,C9P22,C9P24,C9P25,C9P26,C9R5,C9R7,C9R10,C9R11,C9T4,C9T6,C9T9,C9U3,C9U4,C9U6,C25W29,C25W46	108	Conditional	X6S	C95333-007	?	?
CAP_0805-10UF,16V,10%,X7R,G10601-001	C1A4,C1A16,C1B7,C1U20,C3D22,C4A4,C4A17,C4B11,C6T2,C6U10,C6U18,C9T8,C9U8,C9U11	14	Design	X7R	G10601-001	?	?
CAP_0805-22UF,6.3V,20%,X6S,C95333-008	C2L45,C2T6,C2T7,C2T9,C8A14,C8E7,C8E9	7	Conditional	X6S	C95333-008	?	?
CAP_0805-47UF,4V,20%,X6S,C95333-006	C2L32,C2M11,C2M17,C3T7,C3T9,C4B2,C4B3,C4P1,C4P2,C4P3,C4P4,C4P5,C4P7,C4P9,C4P10,C5P3,C5P4,C5P5,C5P6,C5P10,C5P11,C5P12,C5P13,C5P14,C5P15,C5P16,C5P17,C5P18,C5P19,C5P20,C5P21,C5P22,C5P23,C5P24,C5P25,C5P26,C5P27,C5P28,C5P29,C5P30,C5P31,C5P32,C5P33,C5P34,C5P35,C5P36,C5P37,C5P40,C5P41,C5P42,C5P43,C5P44,C6B3,C6U2,C6U3,C7A31,C7A32,C7A33,C7B4,C7B7,C7P1,C7P2,C7P3,C7P4,C7P5,C7P6,C7P7,C7P8,C7P9,C7P10,C7P11,C7P13,C7P14,C7P15,C7P17,C7P18,C7P19,C7P20,C8A12,C8A13,C8B15,C8B16,C8P3,C8P4,C8P8,C8P9,C8P10,C8P11,C8P12,C8P13,C8P14,C8P15,C8P16,C8P17,C8P18,C8P19,C8P20,C8P21,C8P22,C8P23,C8P24,C8P25,C8P26,C8P27,C8P28,C8P29,C8P32,C8P33,C8P34	109	Conditional	X6S	C95333-006	?	?
CAP_0805LF-22UF,4V,20%,X6S,C95333-002	C1A1,C1A12,C1G17,C1G20,C4A1,C4A13,C4G20,C4G24,C5P1,C5P2,C5P7,C5P8,C5P9,C5P38,C5P39,C6A1,C6A4,C6G3,C7A30,C7A42,C7G27,C8P1,C8P2,C8P5,C8P6,C8P7,C8P30,C8P31,C9F4,C9F13,C9W13	31	Conditional	X6S	C95333-002	?	?
CAP_1206-0.068UF,50V,20%,X7R,108427-047	C1E2	1	Archive	X7R	108427-047	?	?
CAP_1206LF-22UF,16V,10%,X6S,D38464-005	C2P10,C7E11,C8E10	3	Conditional	X6S	D38464-005	?	?
CAP_1210-100UF,16V,20%,X5R,644066-127	C4E8,C4E9,C4E14,C7A13,C7A14,C7C7,C7C8	7	Design	X5R	644066-127	?	?
CAP_1210-47UF,16V,20%,EMPTY,D38464-007	C9E6,C9F2	2	Design	EMPTY	D38464-007	?	?
CAP_1210-47UF,16V,20%,X6S,D38464-007	C1G2,C1G7,C1G12,C1G15,C4B1,C4G5,C7B8,C7E12,C7E13,C7F7,C8E11,C9F1	12	Design	X6S	D38464-007	?	?
CAP_A_0402V-0.01UF,25V,10%,EMPTY,A36096-045	C8F6,C8F11,C8F13,C8F15	4	Approved	EMPTY	A36096-045	?	?
CAP_A_0402V-0.01UF,25V,10%,X7R,A36096-045	C1A5,C1A17,C1B9,C1B15,C1B17,C1F9,C1F19,C1F22,C1G8,C1G10,C1G18,C1G19,C1L2,C1L3,C1L6,C1L7,C1L12,C1L13,C1L14,C1L15,C1L20,C1M28,C1M30,C1M31,C1M34,C1M35,C1M36,C2L3,C2L4,C2L5,C2L6,C2L7,C2L9,C2L10,C2L12,C2L13,C2L14,C2L15,C2L16,C2L17,C2L18,C2L19,C2L20,C2L21,C2L22,C2L23,C2L24,C2L26,C2L27,C2L28,C2L29,C2L30,C2L31,C2L33,C2L34,C2L35,C2L36,C2L37,C2L38,C2L39,C2L40,C2L41,C2L42,C2L43,C2L44,C2L47,C2L48,C2L49,C2L50,C2L51,C2L52,C2P8,C2T18,C2T27,C2T37,C3T5,C4A5,C4A18,C4B12,C4F9,C4F10,C4G1,C4G3,C4G17,C4G19,C6L1,C6L2,C6L6,C6L7,C6M1,C6M2,C6T1,C6U9,C6U17,C7F1,C8F5,C9L1,C9L3,C9L7,C9L8,C9M1,C9M2,C9T1,C9T7,C9U7,C9U10	106	Approved	X7R	A36096-045	?	?
CAP_A_0402V-0.1UF,16V,10%,EMPTY,A36096-030	C1B16,C1D22,C2M3,C2M4,C3D27,C3P1,C4C2,C9P12,C9P16,C9P17,C25W20,C25W21	12	Approved	EMPTY	A36096-030	?	?
CAP_A_0402V-0.1UF,16V,10%,X7R,A36096-030	C1A10,C1A20,C1B2,C1B5,C1B19,C1C9,C1C14,C1C17,C1C25,C1D9,C1D11,C1D13,C1D21,C1D26,C1D27,C1D28,C1D34,C1E14,C1E16,C1E17,C1E20,C1E22,C1F28,C1G14,C1G22,C1G25,C1L4,C1L8,C1L9,C1L11,C1L16,C1L17,C1M20,C1M22,C1M23,C1M24,C1M29,C1M33,C1M38,C1R14,C1R15,C1R18,C1R19,C1R20,C1R21,C1R24,C1R25,C1R26,C1R27,C1R28,C1R29,C1R31,C1T3,C1T5,C1T10,C1T11,C1T56,C1U22,C2L11,C2M23,C2M24,C2P1,C2P2,C2P3,C2P4,C2P5,C2P6,C2P7,C2P9,C2P11,C2P12,C2P13,C2P14,C2P15,C2P16,C2R1,C2R2,C2R3,C2R4,C2R5,C2R15,C2R16,C2R17,C2R18,C2T1,C2T2,C2T3,C2T4,C2T5,C2T8,C2T12,C2T15,C2T16,C2T17,C2T21,C2T24,C2T25,C2T26,C2T29,C2T30,C2T32,C2T34,C2T35,C2T36,C2U19,C2U20,C2U21,C2U22,C2U23,C2U24,C2U25,C2U27,C2U28,C3B4,C3B5,C3F2,C3L31,C3N29,C3P5,C3P7,C3P43,C3P44,C3P46,C3P47,C3P48,C3P49,C3P51,C3P52,C3R1,C3R2,C3R3,C3U10,C4A20,C4C10,C4C19,C4D11,C4D19,C4D22,C4D24,C4D26,C4D32,C4D35,C4D38,C4D49,C4E13,C4E20,C4G22,C4G25,C4R2,C6F1,C6F2,C6F3,C6M6,C6P4,C6P5,C6P6,C6P9,C6P10,C6P11,C6P12,C6U5,C6W3,C7A5,C7A20,C7A38,C7A39,C7A40,C7B2,C7B6,C7C11,C7D1,C7D5,C7E1,C7E2,C7E3,C7E4,C7E5,C7E9,C7F6,C7F15,C7F17,C7G29,C7G36,C8A8,C8B5,C8B7,C8B8,C8C8,C8C9,C8C10,C8C11,C8C12,C8C13,C8C14,C8C15,C8D1,C8D2,C8D4,C8E1,C8E2,C8E3,C8E5,C8E8,C8E18,C8E19,C8F16,C8F17,C9A1,C9A2,C9A3,C9A4,C9A5,C9B7,C9B10,C9E4,C9E5,C9F5,C9F19,C9F23,C9G4,C9G6,C9G7,C9G19,C9M5,C9M6,C9M7,C9M8,C9M9,C9M11,C9P6,C9P11,C9P15,C9R6,C9R12,C9R13,C9R14,C9U12,C9W5,CT1,CT6,CT7,CT12,CT13,CT16,CT21,CT24,CT25,CT30,CT31,CT36,CT39,CT40,CT45,CT46,CT51,CT52,CT57,CT60,CT63,CT66,CT67,CT70	262	Approved	X7R	A36096-030	?	?
CAP_A_0402V-1.0UF,6.3V,10%,X6S,D97712-004	C1A2,C1A11,C1B3,C1B6,C1C3,C1C7,C1C13,C1C18,C1D5,C1D15,C1E6,C1E23,C1F21,C1G4,C1G23,C1G27,C1L5,C1L10,C1L18,C1M3,C1M21,C1M25,C1M32,C1M37,C1T21,C2L8,C2M6,C2M7,C2M8,C2M9,C2M16,C2M18,C2M19,C2M20,C2M21,C2M22,C2M25,C2N2,C2N3,C2N4,C2N5,C2N7,C2N8,C2N9,C2N11,C2N12,C2N13,C2N15,C2N16,C2N18,C2N19,C2N20,C2N25,C2N26,C2R12,C2T19,C2T28,C2T31,C2T33,C2T38,C2U26,C3C1,C3C2,C3L1,C3L29,C3M19,C3M20,C3M21,C3M22,C3M27,C3M29,C3M30,C3M31,C3M38,C3M39,C3M42,C3M43,C3M46,C3N1,C3N2,C3N3,C3N4,C3N5,C3N6,C3N7,C3N15,C3N16,C3N17,C3N18,C3N19,C3N20,C3N21,C3N22,C3N23,C3N25,C3N32,C3N40,C3P3,C3P4,C3P42,C3T4,C4C3,C4C4,C4C14,C4D6,C4D14,C4D15,C4D23,C4D25,C4D27,C4D31,C4D36,C4E6,C4E25,C4E28,C4F1,C4F3,C4T1,C4T2,C7A18,C7A26,C7A37,C7B1,C7C19,C7C20,C7F2,C7F16,C7F18,C7G35,C7G42,C8A7,C8F4,C9A6,C9B9	134	Conditional	X6S	D97712-004	?	?
CAP_A_0603V-22.0UF,4V,20%,EMPTY,E15431-004	C9E1,C9E12	2	Design	EMPTY	E15431-004	?	?
CAP_A_0603V-22.0UF,4V,20%,X6S,E15431-004	C1C19,C1D3,C1D14,C1D24,C1E3,C1E9,C2A1,C2A2,C2A3,C2A4,C2A6,C2A7,C2A9,C2A10,C2A11,C2A12,C2A13,C2A14,C2A15,C2D1,C2D2,C2D3,C2D12,C2D13,C2D14,C2D15,C2D16,C2D17,C2D18,C2D19,C2D20,C2D21,C2D22,C2D23,C2D24,C2D25,C2D26,C2D27,C2D28,C2D29,C2D30,C2D31,C2D32,C2D33,C2D34,C2D35,C2D36,C2D37,C2D38,C2D39,C2D40,C2D45,C2D46,C2D47,C2G1,C2G2,C2G3,C2G4,C2G5,C2G6,C2G9,C2G10,C2G11,C2G12,C2G13,C2G14,C2M1,C2M2,C2M12,C2M13,C2N10,C3A1,C3A2,C3A5,C3A6,C3D1,C3D2,C3D4,C3D5,C3D6,C3D7,C3D8,C3D9,C3D10,C3D11,C3D12,C3D13,C3D14,C3D15,C3D16,C3D17,C3D18,C3D19,C3D20,C3D21,C3D23,C3D24,C3D25,C3E1,C3G1,C3G2,C3G5,C3G6,C3L22,C3L23,C3L24,C3L25,C3L26,C3L27,C3M6,C3M7,C3N10,C3N11,C3N12,C3N24,C3N27,C3N28,C3N30,C3N31,C4C11,C4D4,C4D12,C4D34,C4E3,C4E11,C4M2,C4P6,C4P8,C5A1,C5A2,C5A3,C5A4,C5A6,C5A7,C5A8,C5A9,C5A11,C5A12,C5A13,C5A14,C5A15,C5A16,C5A17,C5A18,C5A19,C5D1,C5D2,C5D3,C5D4,C5D5,C5D14,C5D15,C5D16,C5D17,C5D18,C5D19,C5D20,C5D21,C5D22,C5D23,C5D24,C5D25,C5D26,C5D27,C5D28,C5D29,C5D30,C5D31,C5D32,C5D33,C5D34,C5D35,C5D36,C5D37,C5D38,C5D39,C5D40,C5D41,C5D42,C5D43,C5D44,C5D45,C5D46,C5D47,C5D48,C5D49,C5D50,C5D51,C5D52,C5D53,C5D58,C5D59,C5D60,C5D61,C5G1,C5G2,C5G3,C5G4,C5G5,C5G6,C5G7,C5G8,C5G11,C5G12,C5G13,C5G14,C5G15,C5G16,C5G17,C5G18,C5L6,C5L7,C5L8,C5L9,C5L10,C5L11,C5L12,C5L13,C5M1,C5M2,C5M4,C5M5,C5M6,C5M7,C5T5,C5T6,C5T7,C5T8,C5T9,C5T10,C5T11,C5T12,C5U2,C5U3,C5U4,C5U5,C5U6,C5U7,C5U8,C5U9,C6D2,C6D3,C6D4,C6D5,C6D6,C6D7,C6D8,C6D9,C6D10,C6N7,C6P3,C6P16,C6P21,C6R2,C6R7,C7A36,C7B15,C7B16,C7B17,C7B18,C7B19,C7B20,C7B21,C7B22,C7B23,C7B24,C7C6,C7C9,C7C10,C7D3,C7L4,C7L5,C7M1,C7M2,C7P12,C7P16,C7R1,C7T4,C7T5,C7U1,C7U2,C8B1,C8B2,C8B3,C8B4,C8B9,C8B10,C8B11,C8B13,C8B14,C8L5,C8L6,C8L7,C8L8,C8L9,C8L10,C8M1,C8M3,C8M4,C8M5,C8M6,C8T5,C8T6,C8T7,C8T8,C8T9,C8T10,C8U2,C8U3,C8U4,C8U5,C8U6,C8U7,C9N22,C9P3,C9P10,C9P20,C9R2,C9R8	319	Design	X6S	E15431-004	?	?
CAP_A_0603V-22.0UF,4V,20%,X6S,E15431-004	C5G41,C5G42,C5G43,C5G44,C5G45,C5G46,C5G47,C5G48,C5G49,C5G50,C5G51,C5G52,C5G53,C5G54,C5G55,C5G56,C5G57,C5G58,C5G59,C5G60,C5G61,C5G62,C5G63,C5G64,C5G65,C5G66,C5G67,C5G68,C5G69,C5G70,C5G71,C5G72,C5G73,C5G74,C5G75,C5G76,C5G79,C5G80,C5G81,C5G82,C5G83,C5G84,C5G85,C5G86,C5G87,C5G88,C5G89,C5G90,C5G91,C5G92,C5G93,C5G94,C5G95,C5G96,C5G97,C5G98,C5G99,C5G100,C5G101,C5G102,C5G103,C5G104,C5G105,C5G106,C5G107,C5G108,C5G109,C5G110,C5G111,C5G112,C5G113,C5G114	72	Design	X6S	E15431-004	?	1S
CAP_A_0603V-47UF,4V,20%,X5R,602433-106	C2A5,C2B1,C2B2,C2F1,C2F2,C2G8,C2G15,C3F1,C3T1,C3T2,C4F2,C4M5,C5A5,C5B1,C5B2,C5F1,C5F2,C5G10,C5G19,C5L4,C5L5,C5L15,C5M3,C5M9,C5M10,C5M11,C5M13,C5T1,C5T2,C5T3,C5T4,C5T13,C5U11,C5U12,C5U16,C7M5,C8L3,C8L4,C8L12,C8M2,C8M8,C8M9,C8M10,C8M12,C8T1,C8T2,C8T3,C8T4,C8T11,C8U9,C8U10,C8U13	52	?	X5R	602433-106	?	?
CHOKE_4PIN_SMLF-90 OHM,EMPTY,752402-015	L1M2	1	Approved	EMPTY	752402-015	?	?
CONN12_C73564003_PIP-CONN,C73564-003	J7G3,J8G2,J9G1	3	?	CONN	C73564-003	?	?
CONN12_G98257001_THMT-CONN,G98257-001	J1D1,J1E1	2	Design	CONN	G98257-001	?	?
CONN14_H54902001_PIP-CONN,H54902-001	J9A2	1	?	CONN	H54902-001	?	?
CONN17_H71061002_PIP1-CONN,H71061-002	JA9G1	1	?	CONN	H71061-002	?	?
CONN36_G97614001_CP-CONN,G97614-001	J8A2	1	Design	CONN	G97614-001	?	?
CONN3_C95678002_PIP-CONN,C95678-002	J1B3,J8C1,J8D4,J9B2	4	?	CONN	C95678-002	?	?
CONN3_G98259001_PIP-CONN,G98259-001	RM1E1	1	Design	CONN	G98259-001	?	?
CONN4_D42317002_PIP-CONN,D42317-002	J9A1	1	?	CONN	D42317-002	?	?
CONN4_H73295001_PIP-CONN,H73295-001	J2L1	1	?	CONN	H73295-001	?	?
CONN4_H73295001_PIP-EMPTY,H73295-001	J8A4	1	?	EMPTY	H73295-001	?	?
CONN6_C74770005_PIP-HDR,C74770-005	J1B2,J1F2	2	?	HDR	C74770-005	?	?
CONN72_G97614002_A_CP-CONN,G97614-002	J8A1	1	Design	CONN	G97614-002	?	?
CONN76_H22707001_THMT1-CONN,H22707-001	J1C1,J1F1	2	Design	CONN	H22707-001	?	?
CONN7_E82125014_PIP_TH-CONN,E82125-014	J2M1	1	?	CONN	E82125-014	?	?
CONN7_E82125014_PIP_TH-EMPTY,E82125-014	J8A3	1	?	EMPTY	E82125-014	?	?
CONN8_C77962004_PIP-CONN,C77962-004	J7G2	1	?	CONN	C77962-004	?	?
CONN8_H62179001_PIP-CONN,H62179-001	J1F3	1	?	CONN	H62179-001	?	?
CONN9_H51826001_PIP2-CONN,H51826-001	J9B1	1	?	CONN	H51826-001	?	?
CRYSTAL_2013-25.000MHZ,IC,D71700-057	Y9E1	1	?	IC	D71700-057	?	?
CRYSTAL_2013-25.000MHZ,IC,H19611-001	Y8C1	1	Design	IC	H19611-001	?	?
CRYSTAL_2013-48.000MHZ,IC,D71700-058	Y7C1	1	Design	IC	D71700-058	?	?
CRYSTAL_2013LF-25.000MHZ,IC,D71700-033	Y8F1	1	Design	IC	D71700-033	?	?
CRYSTAL_SM-24.000MHZ,IC,D95126-001	Y9F1	1	Preliminary	IC	D95126-001	?	?
CRYSTAL_SM-32.768KHZ,IC,C13544-023	Y7C2	1	?	IC	C13544-023	?	?
CSD87384M_SM-IC,H66258-001	EU8E1	1	?	IC	H66258-001	?	?
DIODE2A_DUAL_SMLF-BAS70-05,DIO,C90169-001	CR2U1	1	Conditional	DIO	C90169-001	?	?
DIODEAC_DUAL_ARRAY_SM9-ESD3V3U4ULC,IC,G18435-001	CR1M2	1	Conditional	IC	G18435-001	?	?
DIODE_SM-1N4148W,IC,D89194-001	CR1L1,CR1L2,CR1L3,CR1L4	4	Design	IC	D89194-001	?	?
DIODE_SM-MBRS340T3G,EMPTY,C81983-002	CR1F5	1	Design	EMPTY	C81983-002	?	?
DIODE_SM-SDMK0340L,EMPTY,H71799-001	CR1B1,CR1E1	2	?	EMPTY	H71799-001	?	?
DIODE_SM-SDMK0340L,IC,H71799-001	CR1B2,CR1B3,CR1F1,CR1F2,CR1F3,CR1F4	6	?	IC	H71799-001	?	?
DIODE_SMLF-1N5819HW,IC,D55839-001	CR3U1	1	Conditional	IC	D55839-001	?	?
DIODE_SMLF-BAT54WS,IC,C73510-001	CR7E1,CR8E1,CR9P1,CR9P2	4	Conditional	IC	C73510-001	?	?
FERRITE_SM-120,FB,693286-027	FB2M1,FB2M2,FB3M1,FB3M2,FB3M3,FB3M4	6	Conditional	FB	693286-027	?	?
FERRITE_SM-22,FB,656554-051	FB4A1,FB4G1,FB7B1,FB7E1,FB7F1,FB9E1	6	Design	FB	656554-051	?	?
FERRITE_SMLF-30,FB,693286-021	FB1U3,FB1U4	2	Approved	FB	693286-021	?	?
FERRITE_SMLF-60,FB,693286-001	FB1U2	1	Approved	FB	693286-001	?	?
FERRITE_SMLF-600,FB,656554-043	FB2T2,FB6P1	2	Conditional	FB	656554-043	?	?
FET_N_DUAL_SMLF-2N7002DW,FET,D24280-001	Q1D1,Q1L4,Q6W2,Q9P1	4	Approved	FET	D24280-001	?	?
FET_N_DUAL_SMLF-NTJD4001N,FET,E40049-001	Q1L2,Q2U1,Q3U1,Q4B1,Q4B2,Q4U1,Q7E1,Q7E2,Q7E3,Q7E5,Q7E6,Q9A2,Q9E1,Q9F1,Q9G1	15	Conditional	FET	E40049-001	?	?
FET_N_SOT23-2N7002,FET,C79254-001	Q2P2,Q6F1,Q7D1,Q7E4,Q7E8,Q8D2	6	Approved	FET	C79254-001	?	?
FET_N_SOT23LF-2N7002,FET,C79254-001	Q1D2,Q2P1,Q2T2,Q6W1,Q8E1,Q8E2,Q8F1,Q8F2,Q9A3,Q9W1	10	Approved	FET	C79254-001	?	?
FSA3357_SM-IC,C63273-001	U9F1,U9F2	2	Design	IC	C63273-001	?	?
FUSE_SM-IC,C94311-016	F9B1	1	Conditional	IC	C94311-016	?	?
FUSE_SMLF-IC,C94311-006	F8B1	1	Conditional	IC	C94311-006	?	?
FUSE_SMT-IC,H45581-001	F1L1	1	?	IC	H45581-001	?	?
GTL2014_SM-IC,D66151-001	U2T4,U3P1,U3P2,U4C2,U7D2,U9G1	6	Unqual	IC	D66151-001	?	?
H5AN4G6NAFR-TFC-GP_MEMORY-G2-H5AN4G6NAFR-TFC-GP,072.00546.0A0U	U25W5	1	?	?	072.00546.0A0U	?	?
HCB1608KF-800T30-GP_DISCRET-G9-HCB1608KF-800T30-GP,68.00230.231	FB2T1,FB2T3,FB2T4,FB2T5,FB2T6,FB2T7	6	?	?	68.00230.231	?	?
ICS9FGP204_MLFP-IC,E95226-001	EU8F2	1	Conditional	IC	E95226-001	?	?
INDUCTOR_SM-0.12UH,IND,D92183-034	L1A1,L1A2,L1C2,L1D1,L1D2,L1D3,L1E1,L1F2,L1G1,L4C3,L4D1,L4D2,L4D3,L4E1,L7A1,L7A3,L7G1,L7G2	18	DESIGN	IND	D92183-034	?	?
INDUCTOR_SM-0.3UH,IND,D92183-036	L1C1,L4C2,L7A2,L7A4	4	DESIGN	IND	D92183-036	?	?
INDUCTOR_SM-0.47UH,IND,E13358-018	L4A1,L4G1,L7B1,L7F1	4	UNQUAL	IND	E13358-018	?	?
INDUCTOR_SM-1.00UH,IND,E98679-006	L8F1	1	DESIGN	IND	E98679-006	?	?
INDUCTOR_SM-100NH,IND,D92183-019	L1B2,L4C1	2	DESIGN	IND	D92183-019	?	?
INDUCTOR_SM-100NH,IND,D92183-020	L1B1,L1F1,L7A5,L7C1,L7F2	5	DESIGN	IND	D92183-020	?	?
INDUCTOR_SM-150NH,IND,D92183-021	L4E2,L7C2	2	DESIGN	IND	D92183-021	?	?
INDUCTOR_SM-2.2UH,IND,E98761-003	L8E1	1	DESIGN	IND	E98761-003	?	?
INDUCTOR_SMT-0.022UH,IND,721891-082	L2M1	1	?	IND	721891-082	?	?
IR354XX_SM-IR35411,IC,H73688-001	EU1A1,EU1A2,EU1C3,EU1D1,EU1D3,EU1D4,EU1E2,EU1F1,EU1G1,EU4C2,EU4D1,EU4D3,EU4D6,EU4E1,EU7A1,EU7A4,EU7G2,EU7G3	18	?	IC	H73688-001	?	?
IR354XX_SM-IR35412,IC,H73684-001	EU1C1,EU4C1,EU4E2,EU7A2,EU7A3,EU7C1	6	?	IC	H73684-001	?	?
LBG_CORE_QAT_EXT_D_BGA1-IC,H91415-002	U7C1	1	?	IC	H91415-002	?	?
LCMXO2_A_256BGA-IC,H63395-001	U8D7	1	?	IC	H63395-001	?	?
LED_1NC-BLUE,IC,C96565-012	DS9A1	1	Design	IC	C96565-012	?	?
LED_1NCLF-GREEN,IC,C96565-011	DS9A2	1	Design	IC	C96565-011	?	?
LED_1NCLF-YELLOW,IC,C96565-003	DS9A3	1	Design	IC	C96565-003	?	?
LED_A1-RED,IC,D14725-005	DS9F1	1	Approved	IC	D14725-005	?	?
LED_A1LF-GREEN,IC,C97278-010	DS9A5,DS9A6,DS9E1	3	Design	IC	C97278-010	?	?
LED_A1LF-GREEN,IC,D14725-022	DS9A4,DS9A7	2	Conditional	IC	D14725-022	?	?
LMV331IDCKRG4-GP_DISCRET-G-LMV331IDCKRG4-GP,74.00331.A2F	Q9W4	1	?	?	74.00331.A2F	?	?
M25PE16_SM-IC,H77797-001	U9E1	1	?	IC	H77797-001	?	?
MAX9634_SOT-IC,H35789-001	U1B1,U1F1,U4B1,U4F1	4	Design	IC	H35789-001	?	?
MIC5166_DFN-IC,H55101-001	EU4A1,EU4A2,EU4G2,EU4G3	4	?	IC	H55101-001	?	?
MOSFETN_1D3S_SOT5-IC,G68777-001	EU1E1,EU1E3,EU9R1	3	Design	IC	G68777-001	?	?
MOSFET_N_LCC3-BSZ019N03LS,NFET,G26762-001	Q1B1,Q7E7,Q8B1,Q8G1	4	?	NFET	G26762-001	?	?
MTG_KEYHOLE_TH-EMPTY,NA	TH1A1,TH4A1,TH4G1,TH7A1,TH7G1,TH9A1,TH9G1	7	?	EMPTY	NA	?	?
NB3W1200L_LCC-IC,H13585-001	EU4D2	1	Design	IC	H13585-001	?	?
NC7SB3157_SMLF-IC,C99406-001	U1M2,U1M7,U2M1	3	Conditional	IC	C99406-001	?	?
NCP3232L_SM-IC,H86355-001	EU4A3,EU4G1,EU7B1,EU7F1	4	?	IC	H86355-001	?	?
NPN_DUAL_SSOPLF-MBT3904,EMPTY,C52264-001	Q9A1	1	Approved	EMPTY	C52264-001	?	?
NPN_DUAL_SSOPLF-MBT3904,XSTR,C52264-001	Q8D1	1	Approved	XSTR	C52264-001	?	?
NPN_SM-MMBT3904,IC,C52245-001	Q1D3,Q1L3,Q2T1,Q6W3,Q9T1,Q9W2,Q9W3	7	Approved	IC	C52245-001	?	?
OSC_C_6P10-156.25MHZ,OSC,G63831-004	Y3F1,Y6F1	2	?	OSC	G63831-004	?	?
OSC_C_SM4-24MHZ,OSC,D34520-021	Y9F2	1	?	OSC	D34520-021	?	?
PCA9515ADGKR-1-GP_DISCRET-G5-PCA9515ADGKR-1-GP,71.09515.F0W	U6W2	1	?	?	71.09515.F0W	?	?
PCA9517_SM-IC,G77073-001	U1B2	1	Design	IC	G77073-001	?	?
PCA9555PWRG4-GP_DISCRET-G5-PCA9555PWRG4-GP,71.09555.B0W	U6W1	1	?	?	71.09555.B0W	?	?
PCA9617_SSOP-IC,G81764-001	U3B1,U4G1,U6F1,U7E1	4	Design	IC	G81764-001	?	?
PI3B3257A_TSSOPLF-IC,E16801-001	U2T1,U8F1	2	Design	IC	E16801-001	?	?
PI7C9X1172_QFN-IC,H66899-001	EU9F3	1	?	IC	H66899-001	?	?
PNP_TO92-MPS2907,IC,G73554-001	Q1E1,Q9B1	2	Design	IC	G73554-001	?	?
PXE1110B_QFN-IC,H89187-001	EU3P1,EU4D5,EU8A1	3	?	IC	H89187-001	?	?
PXE1610B_QFN-IC,H79206-001	EU1C2,EU4D4	2	?	IC	H79206-001	?	?
PXM1310B_QFN-IC,H89186-001	EU1B1,EU1G2,EU7A5,EU7G1	4	?	IC	H89186-001	?	?
RCC_DFX1940_ID4-EMPTY,N_A	TC1A1,TC1G1,TC9A1,TC9F1	4	???	EMPTY	N_A	?	?
RES_0402-0.0,5%,1/16W,CHIP,G21497-005	R1B10,R1B11,R1B14,R1C2,R1C3,R1C5,R1C7,R1C14,R1C23,R1C25,R1D2,R1D3,R1D24,R1D25,R1D44,R1D45,R1E6,R1E7,R1F8,R1G9,R1G10,R1G19,R1G21,R1G27,R1G28,R1L6,R1L12,R1M5,R1M6,R1M10,R1M13,R1M15,R1M16,R1M17,R1M18,R1R1,R1R8,R1T36,R1T37,R1U3,R1U8,R1U11,R1U51,R1U53,R1U54,R1U58,R1U59,R1U60,R2L1,R2L7,R2L14,R2L17,R2N20,R2N21,R2P1,R2P14,R2R4,R2R12,R2T2,R2T17,R2T20,R2T27,R2T32,R2T40,R2T44,R2T60,R2T64,R2T65,R2T66,R2T67,R2T68,R2U37,R2U46,R2U47,R3B3,R3B5,R3D18,R3F2,R3F4,R3L9,R3L10,R3M1,R3M6,R3P1,R3P2,R3P3,R3P11,R3P22,R3P26,R3P34,R3P35,R3P57,R3P58,R3P59,R3T13,R3U3,R3U10,R4A2,R4A3,R4A8,R4A9,R4B1,R4B3,R4B11,R4B13,R4B14,R4C2,R4C4,R4D26,R4D45,R4D47,R4D50,R4D53,R4D54,R4D56,R4D66,R4D67,R4E16,R4E17,R4F1,R4G4,R4G8,R4G16,R4G23,R4G24,R4G25,R4T1,R6B4,R6B5,R6F7,R6F9,R6L6,R6L8,R6L10,R6L11,R6N11,R6N12,R6P18,R6P29,R6P30,R6P34,R6P38,R6P41,R6P42,R6P43,R6U4,R6U5,R6U6,R6U7,R6W17,R6W18,R6W19,R7A11,R7A12,R7A18,R7B9,R7B11,R7B19,R7B20,R7C15,R7C19,R7D23,R7D27,R7D28,R7D36,R7D41,R7E9,R7E13,R7E17,R7E22,R7F8,R7F9,R7F12,R7F21,R7F35,R7G2,R7G4,R7G14,R7G17,R7G21,R8B12,R8B14,R8C24,R8D35,R8D43,R8E1,R8E21,R8E25,R8E26,R8E27,R8E28,R8E33,R8E35,R8E37,R8E38,R8F2,R8F6,R8F11,R8F18,R8F21,R8F38,R8G7,R8G8,R8G10,R8G13,R8G14,R8G17,R8G18,R8G19,R8G21,R8G22,R9A3,R9A8,R9B11,R9B13,R9E14,R9E18,R9E20,R9F27,R9F33,R9F53,R9F54,R9F56,R9F57,R9F58,R9F59,R9F62,R9F64,R9F65,R9F67,R9F69,R9G4,R9G9,R9G11,R9G17,R9G18,R9G19,R9G20,R9G22,R9G24,R9G28,R9G29,R9G32,R9G33,R9G34,R9M3,R9M9,R9M10,R9M11,R9M20,R9M21,R9N5,R9N9,R9N10,R9N12,R9N15,R9N16,R9N17,R9P16,R9P21,R9R9,R9R10,R9R12,R9T1,R9T4,R9T8,R9U7,R9U10,R25W59,R25W74,R25W83,R25W84,R760,R767,R768,R769,R771,R774,R775,R777,R778,R779,R780,R781,R782,R783,R784,R785,RT1,RT3,RT5,RT8,RT9,RT11,RT14,RT15,RT17,RT19,RT21,RT23,RT25,RT28,RT30,RT31,RT33,RT36,RT37,RT40,RT41,RT44,RT46,RT47	312	UNQUAL	CHIP	G21497-005	?	?
RES_0402-0.0,5%,1/16W,EMPTY,G21497-005	R1C9,R1C10,R1C11,R1C31,R1F9,R1T15,R1T23,R1T24,R1T35,R1T38,R1U55,R1U56,R1U57,R1U61,R1U62,R2P12,R2T57,R2T58,R2T59,R2T61,R2T62,R2T63,R2T69,R2T71,R2U14,R2U15,R2U16,R2U17,R2U18,R2U19,R2U20,R2U21,R2U22,R2U23,R2U24,R2U25,R2U26,R2U27,R2U28,R2U29,R2U45,R2U49,R2U50,R2U51,R3D31,R3F1,R3F3,R3F5,R3F6,R3N30,R3P63,R4T2,R6D16,R6F6,R6F8,R6F10,R6F11,R7C2,R7C4,R7C18,R7D37,R7D38,R7D39,R7D40,R7D43,R7G15,R7G16,R7G18,R7G19,R8C23,R8E11,R8E29,R8F37,R8G9,R8G11,R8G12,R8G15,R8G16,R9F24,R9F26,R9F60,R9F63,R9F66,R9F68,R9F70,R9G27,R9G30,R9P15	88	UNQUAL	EMPTY	G21497-005	?	?
RES_0402-1.0,1%,1/16W,CHIP,G21796-090	R3L1,R3L4,R3L6,R3L8,R3N7,R3U6,R3U9,R6N3,R6P10,R6P19,R6P47,R6R2,R6R5,R6R6,R9L4,R9L9,R9N3,R9P8,R9P22,R9P32,R9R2,R9R11,R9U1,R9U12	24	UNQUAL	CHIP	G21796-090	?	?
RES_0402-1.00K,1%,1/16W,CHIP,G21796-026	R1B1,R1B2,R1C28,R1C32,R1C33,R1C36,R1D6,R1D8,R1D36,R1E9,R1E10,R1F5,R1F6,R1G2,R1G3,R1G11,R1G15,R1G16,R1G17,R1L3,R1L13,R1L23,R1L36,R1L38,R1M19,R1M20,R1M21,R1T11,R1T12,R1T29,R1T30,R1U17,R1U18,R1U30,R1U33,R1U63,R1U64,R2L18,R2L22,R2M4,R2N18,R2P2,R2R5,R2T1,R2T5,R2T7,R2T25,R2T50,R2U43,R3M10,R3N15,R3N16,R3P5,R3P6,R3P7,R3P8,R3P18,R3P25,R3P32,R3P36,R3P56,R3R1,R3R2,R3R15,R3W1,R3W2,R4B10,R4C8,R4C9,R4D42,R4D49,R4D58,R4E3,R4E5,R4F4,R4F5,R4G2,R4G3,R4G14,R4G21,R4G22,R4R1,R6L1,R6L2,R6L12,R6L13,R6L16,R6M1,R6N13,R6N14,R6N15,R6P16,R6P20,R6P21,R6T5,R6W21,R6W23,R7B4,R7B5,R7B17,R7D1,R7D2,R7D7,R7D18,R7D26,R7E12,R7E20,R7F19,R7F22,R7F27,R7G27,R7G28,R7G29,R7G31,R8A5,R8A6,R8B2,R8B23,R8B30,R8C4,R8C18,R8D21,R8D27,R8D28,R8E2,R8F5,R9A14,R9A15,R9A17,R9B6,R9B8,R9B9,R9B12,R9B14,R9F50,R9F51,R9L1,R9L2,R9L6,R9L7,R9L11,R9M1,R9N14	143	UNQUAL	CHIP	G21796-026	?	?
RES_0402-1.00K,1%,1/16W,EMPTY,G21796-026	R1C6,R1E5,R1M23,R1T10,R1U15,R1U16,R2N14,R2N24,R2P11,R2R11,R3N17,R3P64,R4C3,R4E15,R7D19,R7E19,R8C17,R8D5,R8E4,R8E6,R8F35,R9A1,RN8F6	23	UNQUAL	EMPTY	G21796-026	?	?
RES_0402-1.0K,0.1%,1/16W,CHIP,G85996-004	R2M6,R2N4,R2T4,R4B9,R4G10,R7B18,R7F17,R8E18	8	DESIGN	CHIP	G85996-004	?	?
RES_0402-1.0M,1%,1/16W,EMPTY,G21796-021	R6L4,R6L5,R6U3,R6U15,R7C11	5	DESIGN	EMPTY	G21796-021	?	?
RES_0402-1.37K,1%,1/16W,CHIP,G21796-095	R7E16,R8D15,R8D17	3	DESIGN	CHIP	G21796-095	?	?
RES_0402-1.5K,1%,1/16W,CHIP,G21796-003	R1B9,R1C16,R1G24,R1U52,R2L10,R2M8,R2N29,R3P16,R4D32,R4D57,R7A16,R7G3	12	DESIGN	CHIP	G21796-003	?	?
RES_0402-1.8K,1%,1/16W,CHIP,G21796-336	R5N2,R5N4,R8B6,R8B7,R8B11,R8B13,R8N1,R8N4	8	?	CHIP	G21796-336	?	?
RES_0402-10.0,1%,1/16W,CHIP,G21796-066	R1B16,R1C21,R1D4,R1D46,R1D47,R1D48,R1D51,R1E1,R1G5,R1L2,R1L11,R1L14,R1L18,R1L20,R1L24,R1L25,R1L30,R1L32,R3N9,R3N19,R3R7,R3R14,R4D39,R4E7,R4E8,R4T3,R4T4,R6N8,R6N9,R6T3,R6T4,R7A7,R7A14,R7A19,R7G9,R7M3,R7M8,R8A1,R8B20,R9P26,R9P27,R9R4	42	UNQUAL	CHIP	G21796-066	?	?
RES_0402-10.0,1%,1/16W,EMPTY,G21796-066	R3D32,R5D6	2	UNQUAL	EMPTY	G21796-066	?	?
RES_0402-10.0K,1%,1/16W,CHIP,G21796-016	R1C34,R1D10,R1D12,R1D19,R1D22,R1D23,R1M11,R1M12,R1M24,R1M25,R1R12,R1T1,R1U6,R1U7,R2N6,R2N9,R2N13,R2N16,R2N23,R2N28,R2P15,R2P16,R2P18,R2P19,R2P21,R2P22,R2R1,R2R3,R2T8,R2T22,R3N10,R3T4,R3T12,R3T14,R3W3,R3W9,R4A5,R4G5,R4G17,R4G18,R4P5,R5N1,R5N3,R5N5,R6F3,R6L9,R6W2,R6W15,R6W16,R7B6,R7C5,R7C8,R7C13,R7C20,R7C21,R7C23,R7D4,R7D8,R7D10,R7D12,R7E5,R7E6,R7F1,R7F14,R7F28,R7F32,R7G22,R7G23,R7G26,R7P13,R8B32,R8D13,R8D30,R8D41,R8D44,R8E3,R8E30,R8E34,R8E36,R8F26,R8F36,R8G20,R8N2,R8N3,R8N5,R9E1,R9E2,R9E3,R9E4,R9E13,R9E22,R9F8,R9F12,R9F13,R9F61,R9P5,R9P6,R9P9,R9P10,R9P11,R9W12,R25W79,R25W80,R25W91,R25W92	105	UNQUAL	CHIP	G21796-016	?	?
RES_0402-10.0K,1%,1/16W,EMPTY,G21796-016	R1E11,R2N12,R3P50,R3R11,R3T9,R4D35,R4D38,R7B7,R7B8,R7F30,R8D16,R8F1,R9P19,R25W67	14	UNQUAL	EMPTY	G21796-016	?	?
RES_0402-100.0,1%,1/16W,CHIP,G21796-017	R1B22,R1B23,R1C4,R1C12,R1E4,R1E8,R1F2,R1L39,R1L41,R1M3,R1M4,R1U37,R2P20,R2R8,R2T39,R3B4,R3D3,R3D28,R3E1,R3M11,R3M12,R3N20,R3N21,R3P49,R3U2,R4C1,R4C5,R4E10,R4E14,R4E18,R4P11,R4P12,R4P15,R6B2,R6D1,R6N2,R6P46,R6T8,R6T9,R7A13,R7D32,R7P19,R7P30,R8C21,R8C26,R8D42,R9A9,R9B7,R9F25,R9N2,R9P1,R9T7,R9U3	53	UNQUAL	CHIP	G21796-017	?	?
RES_0402-100.0,1%,1/16W,EMPTY,G21796-017	R1D28,R3L11,R3P13,R4L2,R4U6,R6P35,R7L2,R7U2,R8B15,R9M7	10	UNQUAL	EMPTY	G21796-017	?	?
RES_0402-100.0K,1%,1/16W,CHIP,G21796-010	R1D11,R1D15,R1D18,R1D32,R1D37,R1D39,R1L9,R1U1,R1U2,R1U4,R1U5,R3M8,R3M9,R8B4,R8D38,R9G26,R9P23,R9P28,R9P29,R9P33,R25W60,R25W61,R25W62,R25W63,R25W64,R25W65,R25W66	27	UNQUAL	CHIP	G21796-010	?	?
RES_0402-100.0K,1%,1/16W,CHIP,G21796-160	R1C13,R3L12,R3P12,R4D27,R4D60,R6W1,R7F34,R8A4,R9M8,R9U11	10	DESIGN	CHIP	G21796-160	?	?
RES_0402-100.0K,1%,1/16W,EMPTY,G21796-010	R2L25,R2L26,R3M5,R3P21,R6P40,R7F20,R8A7,R8E40,R9M5,R9U8	10	UNQUAL	EMPTY	G21796-010	?	?
RES_0402-105.0K,1%,1/16W,CHIP,G21796-099	R1D14	1	DESIGN	CHIP	G21796-099	?	?
RES_0402-110,1%,1/16W,EMPTY,G21796-203	R6P33	1	?	EMPTY	G21796-203	?	?
RES_0402-113,1%,1/16W,CHIP,G21796-341	R8B9	1	?	CHIP	G21796-341	?	?
RES_0402-11K,1%,1/16W,CHIP,G21796-220	R1D42	1	?	CHIP	G21796-220	?	?
RES_0402-12.1K,1%,1/16W,CHIP,G21796-089	R9P24	1	UNQUAL	CHIP	G21796-089	?	?
RES_0402-13K,1.0%,1/16W,CHIP,G21796-221	R9F32,R9W32	2	DESIGN	CHIP	G21796-221	?	?
RES_0402-15.0K,1%,1/16W,CHIP,G21796-107	R6W13,R9A5,R9P18,R9T6	4	UNQUAL	CHIP	G21796-107	?	?
RES_0402-150.0,1%,1/16W,CHIP,G21796-009	R1B8,R1D9,R1G7,R1L15,R1L17,R1U35,R1U41,R2T72,R2T73,R2U40,R2U41,R3P15,R4D51,R4E6,R4P17,R4P20,R4P23,R4P24,R4R2,R4R3,R4R4,R6D9,R6T6,R6T7,R7A17,R7G24,R7P5,R7P18,R7P20,R7P21,R7P27,R7P28,R8A13,R8A14,R9A11,R9G1,R9G2,R9G3	38	DESIGN	CHIP	G21796-009	?	?
RES_0402-150.0K,1%,1/16W,CHIP,G21796-109	R1D20,R9P17	2	UNQUAL	CHIP	G21796-109	?	?
RES_0402-169,1.0%,1/16W,CHIP,G21796-276	R3N1	1	DESIGN	CHIP	G21796-276	?	?
RES_0402-16K,1.0%,1/16W,CHIP,G21796-317	R1D34,R3N29	2	DESIGN	CHIP	G21796-317	?	?
RES_0402-2,1.0%,1/16W,CHIP,G21796-274	R1F4,R1G1,R1G14,R4F3,R4G1,R4G20,R6L3,R6L14,R6M2,R9L3,R9L8,R9M2	12	DESIGN	CHIP	G21796-274	?	?
RES_0402-2.0K,1%,1/16W,CHIP,G21796-001	R1L1,R2L4,R2L5,R2L6,R2L11,R2L12,R2L15,R2L21,R2L23,R3N3,R8C15,R8C16,R9M16,R9M17	14	CONDITIONAL	CHIP	G21796-001	?	?
RES_0402-2.0K,1%,1/16W,EMPTY,G21796-001	R6P32,R6P37	2	CONDITIONAL	EMPTY	G21796-001	?	?
RES_0402-2.2,5%,1/16W,EMPTY,G21497-016	R4A7,R4F6,R7A15,R7F7,R8F3	5	DESIGN	EMPTY	G21497-016	?	?
RES_0402-2.21K,1%,1/16W,CHIP,G21796-112	R1R16,R1R17,R1R18,R1R19,R1R20,R1R21,R1R22,R1R23,R2T29,R4U2,R8F23,R9A7,R9A12,R9A16	14	DESIGN	CHIP	G21796-112	?	?
RES_0402-2.26K,1.0%,1/16W,CHIP,G21796-311	R1D7,R3P61,R4E4,R7D5,R7D9	5	DESIGN	CHIP	G21796-311	?	?
RES_0402-2.26K,1.0%,1/16W,CHIP,G21796-311	R2U5,R2U13	2	DESIGN	CHIP	G21796-311	B	?
RES_0402-2.26K,1.0%,1/16W,EMPTY,G21796-311	R1B13,R1C18,R1D53,R1G6,R2L24,R3N23,R4D31,R4E20,R6P49,R7A9,R7F36	11	DESIGN	EMPTY	G21796-311	?	?
RES_0402-2.26K,1.0%,1/16W,EMPTY,G21796-311	R8G3,R8G6	2	DESIGN	EMPTY	G21796-311	B	?
RES_0402-2.67K,1%,1/16W,CHIP,G21796-180	R8A2	1	DESIGN	CHIP	G21796-180	?	?
RES_0402-2.7K,1%,1/16W,CHIP,G21796-344	R1T4,R1U21,R1U22,R1U49,R9G35,R9P4,R9P20,R25W57,R25W58	9	?	CHIP	G21796-344	?	?
RES_0402-2.7K,1%,1/16W,EMPTY,G21796-344	R1T5,R1T6,R1U23,R1U24,R2N17	5	?	EMPTY	G21796-344	?	?
RES_0402-20.0,1%,1/16W,CHIP,G21796-173	R1B6,R1B7,R1M8,R1M9,R1T7,R1T8,R1U9,R1U10,R1U19,R1U20,R2T49,R2T55,R2T56,R2U1,R2U6,R2U7,R2U9,R2U10,R2U33,R2U34,R3P23,R3P24,R3R8,R3R9,R4D43,R4D44,R4T9,R4T10,R6U13,R6U14,R6W20,R6W22,R7B2,R7B3,R7F25,R7F26,R7M4,R7M5,R8A8,R8A9,R8B27,R8B28,R8C11,R8C12,R8C14,R8C20,R8D3,R8D4,R8D6,R8D7,R8D23,R8D24,R8G4,R8G5,R9F22,R9F23,R9G12,R9G13,R9M12,R9M13,R9M14,R9M15,R9R7,R9R8	64	DESIGN	CHIP	G21796-173	?	?
RES_0402-20.0,1%,1/16W,CHIP,G21796-173	R1U25,R1U31,R2U31,R2U32,R9G14,R9G15	6	DESIGN	CHIP	G21796-173	B	?
RES_0402-20.0,1%,1/16W,EMPTY,G21796-173	R2U8,R2U12,R2U35,R2U36	4	DESIGN	EMPTY	G21796-173	A	?
RES_0402-20.0K,1%,1/16W,CHIP,G21796-040	R1R7,R3N4,R4B5,R4G7,R7B15,R7C10,R7F13,R8E16	8	UNQUAL	CHIP	G21796-040	?	?
RES_0402-20.0K,1%,1/16W,EMPTY,G21796-040	R9A6	1	UNQUAL	EMPTY	G21796-040	?	?
RES_0402-200.0,1%,1/16W,CHIP,G21796-004	R1L22,R1L31,R1M14,R2R9,R2T13,R2T19,R2T26,R2T37,R9E10,R9E11,R9E12	11	UNQUAL	CHIP	G21796-004	?	?
RES_0402-200.0K,1%,1/16W,CHIP,G21796-080	R1U50	1	UNQUAL	CHIP	G21796-080	?	?
RES_0402-22.1,1.0%,1/16W,CHIP,G21796-250	R1B5,R1C30,R1G12,R1T9,R1W9,R2L16,R2T41,R2T42,R2T46,R3M3,R3P20,R4B7,R4D46,R4D63,R4G12,R7B12,R7E15,R7F16,R7F24,R8A11,R8E7,R8F10,R8F27,R9E17,R9E19,R9F1,R9F11,R25W78,R25W85,R25W86,R25W87,R25W88,R25W89,R25W90	34	DESIGN	CHIP	G21796-250	?	?
RES_0402-221,1.0%,1/16W,CHIP,G21796-271	R1C1,R1L33,R2U42,R2U44,R3B1,R6B3,R6N10,R9A20,R9E24,R9F28	10	DESIGN	CHIP	G21796-271	?	?
RES_0402-23.2K,1%,1/16W,CHIP,G21796-114	R8E31	1	DESIGN	CHIP	G21796-114	?	?
RES_0402-24.9K,1%,1/16W,CHIP,G21796-254	R8E39	1	?	CHIP	G21796-254	?	?
RES_0402-240,1.0%,1/16W,CHIP,G21796-294	R1T27,R3D12,R3D24,R3P60,R3R13,R4C10,R4P14,R4P21,R4T5,R4T6,R5D3,R6D6,R6T1,R6T2,R7M2,R7M7,R7P14,R9M18,R9M19,R25W117	20	DESIGN	CHIP	G21796-294	?	?
RES_0402-240,1.0%,1/16W,EMPTY,G21796-294	R3D13,R3D16,R3D17,R3D22,R3D23,R3D25,R3D26,R4P1,R4P6,R4P7,R5D4,R6D7,R6D10,R6D13,R6D14,R6D15,R7P15,R7P22	18	DESIGN	EMPTY	G21796-294	?	?
RES_0402-249,0.1%,1/16W,CHIP,G85996-031	R3D27,R5D5	2	?	CHIP	G85996-031	?	?
RES_0402-249K,1.0%,1/16W,CHIP,G21796-189	R9P7	1	DESIGN	CHIP	G21796-189	?	?
RES_0402-27.4,1%,1/16W,CHIP,G21796-182	R4D1,R4D2,R4D3,R4D4,R4D5,R4D6,R4D7,R4D8,R4D9,R4D10,R4D11,R4D12,R4D13,R4D14,R4D16,R4D17,R4D19,R4D20,R4D21,R4D22,R4D23,R4D25,R4D28,R4D29	24	DESIGN	CHIP	G21796-182	?	?
RES_0402-274K,1.0%,1/16W,CHIP,G21796-331	R9P13	1	DESIGN	CHIP	G21796-331	?	?
RES_0402-3.16K,1%,1/16W,CHIP,G21796-043	R1B12,R3N31,R4C11,R4D64,R4E2,R7A10,R9N7	7	DESIGN	CHIP	G21796-043	?	?
RES_0402-3.32K,1%,1/16W,CHIP,G21796-027	R1R3,R1R9,R9E7,R9F5,R25W116	5	UNQUAL	CHIP	G21796-027	?	?
RES_0402-3.32K,1%,1/16W,EMPTY,G21796-027	R1C35,R1R6,R3P54	3	UNQUAL	EMPTY	G21796-027	?	?
RES_0402-3.3K,5%,1/16W,CHIP,G21497-013	R8B24,R8B26	2	UNQUAL	CHIP	G21497-013	?	?
RES_0402-3.48K,1.0%,1/16W,CHIP,G21796-279	R1U28,R1U44	2	DESIGN	CHIP	G21796-279	?	?
RES_0402-3.74K,1%,1/16W,CHIP,G21796-059	R8D40	1	DESIGN	CHIP	G21796-059	?	?
RES_0402-301.0,1%,1/16W,CHIP,G21796-076	R1L37	1	UNQUAL	CHIP	G21796-076	?	?
RES_0402-33.0K,5%,1/16W,CHIP,G21497-023	R4U4	1	DESIGN	CHIP	G21497-023	?	?
RES_0402-33.2,1%,1/16W,CHIP,G21796-074	R1B4,R1D1,R1D26,R1D30,R1D33,R1G8,R1L26,R1L29,R1U34,R1U36,R1U40,R1U46,R2M1,R2M3,R2M7,R2N1,R2N26,R2P4,R2R2,R2R10,R2T28,R2T30,R2T33,R2T38,R2T47,R3N24,R3N26,R3P42,R3P43,R3P46,R3R3,R3T1,R3T2,R3T10,R3U1,R4A4,R4A6,R4D36,R4D37,R4D65,R4G15,R4G19,R6P45,R7B1,R7C14,R7C16,R7C26,R7D24,R7D25,R7D29,R7D31,R7D34,R7F3,R7F4,R7F23,R7F29,R7F37,R8D11,R8D22,R8D36,R8E5,R8E9,R8E10,R8E13,R8E17,R8E20,R8E24,R8F7,R8F8,R8F12,R8F29,R8G1,R8G24,R8G25,R9A13,R9E5,R9E6,R9E8,R9E9,R9E16,R9F34,R9G31,R9P3,R25W68,R25W69,R25W70,R25W71,R25W72,R25W73,R25W75,R25W81,R25W82,RN8F5	93	UNQUAL	CHIP	G21796-074	?	?
RES_0402-33.2,1%,1/16W,EMPTY,G21796-074	R9A2	1	UNQUAL	EMPTY	G21796-074	?	?
RES_0402-330,5%,1/16W,CHIP,G21497-028	R1L43,R1L44	2	UNQUAL	CHIP	G21497-028	?	?
RES_0402-348,1%,1/16W,CHIP,G21796-340	R7D15	1	?	CHIP	G21796-340	?	?
RES_0402-348,1%,1/16W,EMPTY,G21796-340	R9F20	1	?	EMPTY	G21796-340	?	?
RES_0402-4.02K,1%,1/16W,CHIP,G21796-082	R1G23,R2L9,R3N22,R6P27,R6P28,R7C24,R7G8,R9N8	8	UNQUAL	CHIP	G21796-082	?	?
RES_0402-4.75K,1%,1/16W,CHIP,G21796-072	R1B21,R1B24,R1D21,R1D35,R1E12,R1F1,R1L7,R1L27,R1L28,R1R5,R1U45,R1U48,R2M2,R2M5,R2N7,R2N10,R2N27,R2N32,R2P3,R2P5,R2P13,R2P17,R2R7,R2T3,R2T6,R2T11,R2T34,R2T35,R2U2,R2U4,R2U30,R2U48,R3N11,R3N12,R3N13,R3P44,R3P53,R3R4,R3R10,R3R16,R3T5,R3W6,R3W7,R4D40,R4D41,R4D69,R4D70,R4R5,R4U1,R4U3,R6M4,R6M9,R6P39,R6P48,R6W7,R6W8,R6W9,R6W10,R7C17,R7D3,R7D6,R7D30,R7D42,R7D44,R7E7,R7E10,R7E11,R7E18,R7E21,R7F5,R7F33,R7G7,R8B3,R8B5,R8B8,R8B10,R8B16,R8B17,R8B18,R8B19,R8B25,R8B31,R8C1,R8C2,R8C6,R8C7,R8C9,R8C25,R8D14,R8D25,R8D26,R8D29,R8D31,R8D37,R8E14,R8E22,R8E23,R8E32,R8F13,R8F14,R8F24,R8F34,R8G2,R8G23,R9A18,R9A21,R9E21,R9F3,R9F29,R9F30,R9F47,R9F52,R9F55,R9G21,R9T5,R9T9,R25W94,R25W95,R25W96,R25W98,R25W100,R25W102,R25W108,R25W110,R25W115,R25W119,RN8F1,RN8F2,RN8F3	129	UNQUAL	CHIP	G21796-072	?	?
RES_0402-4.75K,1%,1/16W,EMPTY,G21796-072	R1D27,R1D29,R1L19,R3N2,R3P62,R3T3,R6P22,R6P23,R6W4,R6W5,R6W6,R6W11,R6W12,R7C22,R7F6,R8E12,R8E19,R8F16,R9F48,R9F49,R9G23,R9G25,R25W97,R25W99,R25W101,R25W103,R25W104,R25W105,R25W106,R25W107,R25W109,R25W111,R25W112,R25W113,R25W114,R25W118,RN8F4	37	UNQUAL	EMPTY	G21796-072	?	?
RES_0402-4.99K,1%,1/16W,CHIP,G21796-013	R9E23,R9P12	2	UNQUAL	CHIP	G21796-013	?	?
RES_0402-40.2K,1%,1/16W,CHIP,G21796-133	R1D40	1	DESIGN	CHIP	G21796-133	?	?
RES_0402-42.2,1.0%,1/16W,EMPTY,G21796-259	R4D18,R4D24,R6P1,R6P2,R6P3,R6P4,R6P5,R6P6,R6P7,R6P8,R6P9,R6P11,R6P12,R6P13,R6P15,R6P17,R7P1,R7P2,R7P3,R7P4,R7P6,R7P7,R7P9,R7P12	24	DESIGN	EMPTY	G21796-259	?	?
RES_0402-470.0,5%,1/16W,CHIP,G21497-024	R1L8	1	UNQUAL	CHIP	G21497-024	?	?
RES_0402-475.0,1%,1/16W,CHIP,G21796-077	R8F25,R9A4	2	UNQUAL	CHIP	G21796-077	?	?
RES_0402-49.9,1%,1/16W,CHIP,G21796-047	R1L16,R1M22,R1U43,R2N19,R2N22,R2N31,R2T18,R2T36,R3B2,R3D4,R3D9,R3D15,R3D19,R3D20,R3L13,R3P45,R4E9,R4P2,R4P3,R4P4,R4P18,R4P19,R4R6,R5P2,R5P3,R5P4,R5R1,R6B1,R6D2,R6D5,R6D8,R6D11,R6D12,R6F1,R6F2,R6F4,R6F5,R6M8,R6N1,R7D33,R7P8,R7P10,R7P11,R7P25,R7P26,R8B29,R8D19,R8D20,R8P1,R8P2,R8P3,R8R1,R9B4,R9B5,R9B10,R9M6,R9N1,R9P2,R9R5,R9R6	60	UNQUAL	CHIP	G21796-047	?	?
RES_0402-49.9,1%,1/16W,EMPTY,G21796-047	R3N14,R3P17,R3T11,R8B21,R9U4	5	UNQUAL	EMPTY	G21796-047	?	?
RES_0402-49.9K,1%,1/16W,CHIP,G21796-048	R2L19,R8D39	2	UNQUAL	CHIP	G21796-048	?	?
RES_0402-5.11K,1%,1/16W,CHIP,G21796-140	R1U26,R1U29,R1U32,R1U39,R1U47,R6W14,R8A10	7	UNQUAL	CHIP	G21796-140	?	?
RES_0402-5.36K,1.0%,1/16W,CHIP,G21796-297	R1B15,R1G22	2	DESIGN	CHIP	G21796-297	?	?
RES_0402-51,5.0%,1/16W,CHIP,G21497-048	R1U12,R1U13,R1U14,R2R6	4	DESIGN	CHIP	G21497-048	?	?
RES_0402-51.1,1.0%,1/16W,CHIP,G21796-208	R2N25,R4A1,R6L7,R6N4,R6U8,R6U16,R7C3,R7P29,R7R1,R8B1,R9N4	11	DESIGN	CHIP	G21796-208	?	?
RES_0402-560,5%,1/16W,CHIP,G21497-062	R2P8	1	?	CHIP	G21497-062	?	?
RES_0402-6.19K,1%,1/16W,CHIP,G21796-161	R1D31,R9T3	2	UNQUAL	CHIP	G21796-161	?	?
RES_0402-6.34K,1%,1/16W,CHIP,G21796-146	R3P51,R4B4,R4G9,R7B13,R7F11	5	DESIGN	CHIP	G21796-146	?	?
RES_0402-63.4K,1.0%,1/16W,CHIP,G21796-327	R2L20	1	DESIGN	CHIP	G21796-327	?	?
RES_0402-64.9,1.0%,1/16W,CHIP,G21796-298	R1L21,R3D21,R3P29,R3P38,R7M9	5	DESIGN	CHIP	G21796-298	?	?
RES_0402-64.9K,1%,1/16W,CHIP,G21796-148	R8F9	1	DESIGN	CHIP	G21796-148	?	?
RES_0402-665,1.0%,1/16W,CHIP,G21796-235	R1T2,R1T3	2	DESIGN	CHIP	G21796-235	B	?
RES_0402-665,1.0%,1/16W,CHIP,G21796-235	R2N5,R2N8,R2T53,R2T54,R2U3,R2U11,R2U38,R2U39,R3R5,R3R12,R4T7,R4T8,R6U17,R6U18,R7M1,R7M6	16	DESIGN	CHIP	G21796-235	?	?
RES_0402-68.1K,1%,1/16W,EMPTY,G21796-187	R1A2,R1A3,R1C37,R1D52,R1D54,R1D55,R1E13,R1E14,R1G25,R1G26,R3L14,R3L15,R4C13,R4D68,R4D71,R4D72,R4E19,R4E21,R4E22,R7A20,R7A21,R7C25,R7G25,R7G30	24	DESIGN	EMPTY	G21796-187	?	?
RES_0402-69.8K,1%,1/16W,CHIP,G21796-007	R1D16	1	DESIGN	CHIP	G21796-007	?	?
RES_0402-7.5K,1%,1/16W,CHIP,G21796-177	R1D43	1	UNQUAL	CHIP	G21796-177	?	?
RES_0402-7.87K,1.0%,1/16W,CHIP,G21796-242	R4B6,R4B8,R4G11,R4G13,R7B14,R7B16,R7F15,R7F18	8	DESIGN	CHIP	G21796-242	?	?
RES_0402-75,1.0%,1/16W,CHIP,G21796-267	R2T9,R2T16,R2T31,R2T43,R3P41,R7E2	6	DESIGN	CHIP	G21796-267	?	?
RES_0402-75K,1%,1/16W,CHIP,G21796-224	R7E14	1	?	CHIP	G21796-224	?	?
RES_0402-8.06K,1%,1/16W,CHIP,G21796-078	R4C12,R7A8,R7G10	3	UNQUAL	CHIP	G21796-078	?	?
RES_0402-8.2K,1%,1/16W,CHIP,G21796-345	R1T25,R1T26,R1U27,R1U38	4	?	CHIP	G21796-345	?	?
RES_0402-8.2K,1%,1/16W,EMPTY,G21796-345	R7D13	1	?	EMPTY	G21796-345	?	?
RES_0402-90.9,1%,1/16W,CHIP,G21796-365	R3D1,R3D2,R4P8,R4P10,R5D1,R5D2,R7P16,R7P17	8	?	CHIP	G21796-365	?	?
RES_0402-90.9K,1%,1/16W,CHIP,G21796-058	R1D13,R3P48	2	UNQUAL	CHIP	G21796-058	?	?
RES_0603-0,5.0%,1/10W,CHIP,G22178-002	R1R15,R1T32,R1T34	3	UNQUAL	CHIP	G22178-002	?	?
RES_0603-0,5.0%,1/10W,EMPTY,G22178-002	R1T33	1	UNQUAL	EMPTY	G22178-002	?	?
RES_0603-10.0,1%,1/10W,CHIP,G22026-041	R2L8,R9P30	2	UNQUAL	CHIP	G22026-041	?	?
RES_0603-100.0,1%,1/10W,CHIP,G22026-038	R1E3,R4E13	2	DESIGN	CHIP	G22026-038	?	?
RES_0603-100.0K,1%,1/10W,CHIP,G22026-050	R5P1,RT8P1	2	DESIGN	CHIP	G22026-050	?	?
RES_0603-10M,1.0%,1/10W,CHIP,G22026-112	R7C6	1	DESIGN	CHIP	G22026-112	?	?
RES_0603-120.0,1%,1/10W,CHIP,G22026-003	R1A1,R1G20,R3U4,R4B2,R4G6,R4L4,R7B10,R7F10	8	DESIGN	CHIP	G22026-003	?	?
RES_0603-2.2,1.0%,1/10W,CHIP,G22026-127	R2T21,R2T23,R2T52,R3D14,R6P25	5	DESIGN	CHIP	G22026-127	?	?
RES_0603-200K,0.1%,1/10W,CHIP,G22369-010	R7C1	1	?	CHIP	G22369-010	?	?
RES_0603-475.0,1%,1/10W,CHIP,G22026-030	R8A12	1	DESIGN	CHIP	G22026-030	?	?
RES_0805-0.0,5%,1/8W,CHIP,G22179-004	R1D41	1	UNQUAL	CHIP	G22179-004	?	?
RES_1206-0.002,1%,1W,CHIP,G52199-004	R1F3,R4B12,R4F2,R9M4	4	DESIGN	CHIP	G52199-004	?	?
RES_2010-0.001,1%,1W,CHIP,E30969-002	R1B20,R4C6	2	DESIGN	CHIP	E30969-002	?	?
RES_PWR_6PAD-0.001,1%,3W,CHIP,E74391-005	R1D49,R9R1	2	Design	CHIP	E74391-005	?	?
RT8240_QFN-IC,H66262-001	EU8F1	1	?	IC	H66262-001	?	?
RT9059_DFN-IC,H65765-001	EU8A2,EU9F1,EU9F2,EU25F2	4	?	IC	H65765-001	?	?
SC1U16V3KX-2GP_SMD-BCG-SC1U16V3KX-2GP,78.10521.5BL	C25W17,C25W18	2	?	?	78.10521.5BL	?	?
SC22P50V2JN-4GP_SMD-BCG-SC22P50V2JN-4GP,78.22034.1FL	C9W1,C9W2	2	?	?	78.22034.1FL	?	?
SC2K2P50V3KX-GP_SMD-BCG6-SC2K2P50V3KX-GP,78.22224.2BL	CT3,CT5,CT9,CT11,CT14,CT18,CT20,CT23,CT27,CT29,CT33,CT35,CT38,CT41,CT44,CT47,CT50,CT53,CT56,CT59,CT62,CT65,CT68,CT72	24	NOPOP	?	78.22224.2BL	?	?
SC4D7U10V3KX-GP_SMD-BCG-SC4D7U10V3KX-GP,78.47523.5BL	C25W19,C25W30,C25W36,C25W39,C25W47,C25W50,C25W59,C25W62,C25W65,C25W69,C25W70	11	?	?	78.47523.5BL	?	?
SCD1U16V2KX-3GP_SMD-BCG-SCD1U16V2KX-3GP,78.10421.2FL	C25W14,C25W15,C25W31,C25W34,C25W38,C25W45,C25W49,C25W55,C25W58,C25W61,C25W64,C25W68	12	?	?	78.10421.2FL	?	?
SCONN10_C12536004_SMLF-CONN,C12536-004	J9B4	1	Design	CONN	C12536-004	?	?
SCONN11_H67026001_SM-CONN,H67026-001	J8E1	1	?	CONN	H67026-001	?	?
SCONN120_A28699018_SM-SCONN,A28699-018	J9B3	1	?	SCONN	A28699-018	?	?
SCONN120_H61426002_SM-CONN,H61426-002	J4B2,J4E1,J6B1,J6E1	4	?	CONN	H61426-002	?	?
SCONN200_H68296001_SM-CONN,H68296-001	J8G1	1	?	CONN	H68296-001	?	?
SCONN24_H46321001_SM-SCONN,H46321-001	J8B1	1	?	SCONN	H46321-001	?	?
SCONN288_H44441003_PIP-SCONN,H44441-003	J6L1,J6L2,J6M1,J6T1,J6U1,J6U2,J9L1,J9L2,J9M1,J9T1,J9U1,J9U2	12	?	SCONN	H44441-003	?	?
SCONN288_H44441004_PIP-SCONN,H44441-004	J1A1,J1A2,J1B1,J1G1,J1G2,J1G3,J4A1,J4A2,J4B1,J4G1,J4G2,J4G3	12	?	SCONN	H44441-004	?	?
SCONN3_D53458001_SM-EMPTY,D53458-001	J1B4	1	?	EMPTY	D53458-001	?	?
SCONN60_C21100002_SMLF-CONN,C21100-002	J9A3	1	Unqual	CONN	C21100-002	?	?
SCONN64_H87568002_A_SMT-CONN,H87568-002	J8E4	1	?	CONN	H87568-002	?	?
SCONN75K_H17033002_SMT1-SCONN,H17033-002	J8F1	1	Design	SCONN	H17033-002	?	?
SCONN80_E67482007_SM-CONN,E67482-007	J8E3	1	?	CONN	E67482-007	?	?
SHUNT_SH0201-EMPTY,N_A	SH3D1,SH3D2,SH3P1,SH3P2,SH4L1,SH4L2,SH4U1,SH4U2,SH5L1,SH5U1,SH7L1,SH7L2,SH7U1,SH7U2,SH8L1,SH8U1	16	???	EMPTY	N_A	?	?
SKX_EXT_B_BGA1-IC,TBD	U2D1,U5D1	2	?	IC	TBD	?	?
SLG55021_SM-IC,G56246-001	EU2T1,EU7E1,EU8B1,EU9M1	4	?	IC	G56246-001	?	?
SMC-CONN60A-22-GP_CONN-G7-SMC-CONN60A-22-GP,020.C0082.0060	CONX8	1	?	?	020.C0082.0060	?	?
SNLABEL_A_LABEL-EMPTY,N_A	LB2B1,LB2F1,LB5B1,LB5F1,LB6T1	5	???	EMPTY	N_A	?	?
SOCKET_P_MECH_A_LEFT-P0,PLASTIC,H37604-201	XLU1,XLU2	2	Design	PLASTIC	H37604-201	?	?
SOCKET_P_MECH_A_RIGHT-P0,PLASTIC,H37604-101	XRU1,XRU2	2	Design	PLASTIC	H37604-101	?	?
SPRINGVILLE_SM1-IC,G47144-004	EU9E1	1	Approved	IC	G47144-004	?	?
STANDOFF_TH1-SO,H72821-001	RM8D1	1	?	SO	H72821-001	?	?
SWITCH_D37771002_SM-IC,D37771-002	S9A1	1	Design	IC	D37771-002	?	?
SWITCH_D90553001_SMLF-IC,D90553-001	S8E1	1	Conditional	IC	D90553-001	?	?
SW_H67881001_SM-IC,H67881-001	S9A2	1	?	IC	H67881-001	?	?
TMP421_TSSOP-IC,G62962-001	U1E1,U9B4	2	Design	IC	G62962-001	?	?
TPS2061_SM-IC,H66405-001	U1M3	1	?	IC	H66405-001	?	?
TPS3700_SM-IC,H69492-001	U1D2,U8D8,U9P1,U9P2	4	?	IC	H69492-001	?	?
TPS54821_LCC-IC,H63269-001	EU7E2	1	?	IC	H63269-001	?	?
TTL08_QFN15-74LVC08A,IC,D90404-001	U8E1	1	Conditional	IC	D90404-001	?	?
TTL1G07_A_SOP-74LVC1G07,IC,C88419-001	U1L4,U1R1,U2P1,U8D2,U8D3,U8G2,U8G3,U9A1,U9F3	9	Approved	IC	C88419-001	?	?
TTL1G08_SOTLF-NC7SZ08,IC,D10321-001	U1E2,U1M1,U6W10,U7E2,U7E3	5	Conditional	IC	D10321-001	?	?
TTL1G126_A_SOT-74HC1G126,IC,A79322-001	U1D1,U1R2,U8D5,U8E3,U8E4	5	Conditional	IC	A79322-001	?	?
TTL1G32_A_SOT-74LVC1G32,IC,E60229-001	U2T2,U2T3	2	Preliminary	IC	E60229-001	?	?
TTL1G86_SOTLF-74AHCT1G86,IC,D39848-001	U1L2	1	Design	IC	D39848-001	?	?
TTL2G07_SOT23LF-74LVC2G07,IC,D22707-001	U8F3,U8G1	2	Conditional	IC	D22707-001	?	?
TTL2G14_SMLF-74LVC2G14,IC,D18476-001	U2R1,U9A3,U9A4	3	Approved	IC	D18476-001	?	?
TTL3126_QFNLF-74CBTLV3126,IC,D18317-001	U1L1,U1L5	2	Preliminary	IC	D18317-001	?	?
VERT_BATT_3PIN_PIP-3PVERT,C68619-005	XBT8G1	1	?	3PVERT	C68619-005	?	?
W25Q128_SKT16-IC,H12709-001	U8F2	1	?	IC	H12709-001	?	?
W25Q256_XSOI-IC,H25002-001	U3T1,U7F1,UN8F2	3	Design	IC	H25002-001	?	?
ZENER_SM-13V,IC,H69095-001	VR1D1	1	?	IC	H69095-001	?	?
TOTAL	 	4385	 	 	 	 	 
